(kicad_pcb
	(version 20241229)
	(generator "pcbnew")
	(generator_version "9.0")
	(general
		(thickness 1.62)
		(legacy_teardrops no)
	)
	(paper "A4")
	(title_block
		(title "OCuLink to 10GbE adapter")
		(date "2026-02-23")
		(rev "1.1.0")
		(company "Antmicro Ltd")
		(comment 1 "www.antmicro.com")
		(comment 9 "footprints 162-167 of 510")
	)
	(layers
		(0 "F.Cu" signal)
		(4 "In1.Cu" signal)
		(6 "In2.Cu" signal)
		(8 "In3.Cu" signal)
		(10 "In4.Cu" signal)
		(12 "In5.Cu" signal)
		(14 "In6.Cu" signal)
		(2 "B.Cu" signal)
		(9 "F.Adhes" user "F.Adhesive")
		(11 "B.Adhes" user "B.Adhesive")
		(13 "F.Paste" user)
		(15 "B.Paste" user)
		(5 "F.SilkS" user "F.Silkscreen")
		(7 "B.SilkS" user "B.Silkscreen")
		(1 "F.Mask" user)
		(3 "B.Mask" user)
		(17 "Dwgs.User" user "User.Drawings")
		(19 "Cmts.User" user "User.Comments")
		(21 "Eco1.User" user "User.Eco1")
		(23 "Eco2.User" user "User.Eco2")
		(25 "Edge.Cuts" user)
		(27 "Margin" user)
		(31 "F.CrtYd" user "F.Courtyard")
		(29 "B.CrtYd" user "B.Courtyard")
		(35 "F.Fab" user)
		(33 "B.Fab" user)
	)
	(footprint "antmicro-footprints:LED_0603_1608Metric_G"
		(layer "F.Cu")
		(at 54.35 118.05 180)
		(descr "LED SMD 0603 Green")
		(tags "LED SMD 0603 Green")
		(property "Reference" "D20"
			(at -1.1 -0.75 0)
			(layer "F.SilkS")
			(effects
				(font
					(size 0.7 0.7)
					(thickness 0.15)
				)
				(justify right top)
			)
		)
		(property "Value" "LED_G_0603_LG_L29K-G2J1-24-Z"
			(at -0.001 1.599 0)
			(layer "F.Fab")
			(hide yes)
			(effects
				(font
					(size 0.7 0.7)
					(thickness 0.15)
				)
				(justify right top)
			)
		)
		(property "Datasheet" "https://look.ams-osram.com/m/19ee86b3ae0ee95b/original/LG-L29K.pdf"
			(at 0 0 0)
			(layer "F.Fab")
			(hide yes)
			(effects
				(font
					(size 1.27 1.27)
					(thickness 0.15)
				)
			)
		)
		(property "Description" "LED, Green, SMD, 0603, 20 mA, 1.7 V, 570 nm"
			(at 0 0 0)
			(layer "F.Fab")
			(hide yes)
			(effects
				(font
					(size 1.27 1.27)
					(thickness 0.15)
				)
			)
		)
		(property "MPN" "LG L29K-G2J1-24-Z"
			(at 0 0 180)
			(unlocked yes)
			(layer "F.Fab")
			(hide yes)
			(effects
				(font
					(size 1 1)
					(thickness 0.15)
				)
			)
		)
		(property "Manufacturer" "OSRAM"
			(at 0 0 180)
			(unlocked yes)
			(layer "F.Fab")
			(hide yes)
			(effects
				(font
					(size 1 1)
					(thickness 0.15)
				)
			)
		)
		(property "Color" "Green"
			(at 0 0 180)
			(unlocked yes)
			(layer "F.Fab")
			(hide yes)
			(effects
				(font
					(size 1 1)
					(thickness 0.15)
				)
			)
		)
		(property "Author" "Antmicro"
			(at 0 0 180)
			(unlocked yes)
			(layer "F.Fab")
			(hide yes)
			(effects
				(font
					(size 1 1)
					(thickness 0.15)
				)
			)
		)
		(property "License" "Apache-2.0"
			(at 0 0 180)
			(unlocked yes)
			(layer "F.Fab")
			(hide yes)
			(effects
				(font
					(size 1 1)
					(thickness 0.15)
				)
			)
		)
		(sheetname "/Power/")
		(sheetfile "power.kicad_sch")
		(attr smd)
		(fp_line
			(start 0.22 0.35)
			(end -0.22 0.35)
			(stroke
				(width 0.15)
				(type solid)
			)
			(layer "F.SilkS")
		)
		(fp_line
			(start 0.22 -0.35)
			(end -0.22 -0.35)
			(stroke
				(width 0.15)
				(type solid)
			)
			(layer "F.SilkS")
		)
		(fp_line
			(start 0.105328 0.201008)
			(end 0.105328 -0.198992)
			(stroke
				(width 0.1)
				(type solid)
			)
			(layer "F.SilkS")
		)
		(fp_line
			(start 0.105328 0.201008)
			(end -0.094672 0.001008)
			(stroke
				(width 0.1)
				(type solid)
			)
			(layer "F.SilkS")
		)
		(fp_line
			(start 0.105328 0.001008)
			(end 0.24 0.001)
			(stroke
				(width 0.1)
				(type solid)
			)
			(layer "F.SilkS")
		)
		(fp_line
			(start -0.094672 0.201008)
			(end -0.094672 -0.198992)
			(stroke
				(width 0.1)
				(type solid)
			)
			(layer "F.SilkS")
		)
		(fp_line
			(start -0.094672 0.001008)
			(end 0.105328 -0.198992)
			(stroke
				(width 0.1)
				(type solid)
			)
			(layer "F.SilkS")
		)
		(fp_line
			(start -0.094672 0.001008)
			(end -0.24 0.001008)
			(stroke
				(width 0.1)
				(type solid)
			)
			(layer "F.SilkS")
		)
		(fp_line
			(start -1.18 -0.319)
			(end -1.18 0.321)
			(stroke
				(width 0.15)
				(type solid)
			)
			(layer "F.SilkS")
		)
		(fp_rect
			(start 1.25 0.65)
			(end -1.25 -0.65)
			(stroke
				(width 0.05)
				(type solid)
			)
			(fill no)
			(layer "F.CrtYd")
		)
		(fp_line
			(start 0.599 0)
			(end 0.201 0)
			(stroke
				(width 0.15)
				(type solid)
			)
			(layer "F.Fab")
		)
		(fp_line
			(start 0.201 0.2)
			(end 0.201 0)
			(stroke
				(width 0.15)
				(type solid)
			)
			(layer "F.Fab")
		)
		(fp_line
			(start 0.201 0)
			(end 0.201 -0.202)
			(stroke
				(width 0.15)
				(type solid)
			)
			(layer "F.Fab")
		)
		(fp_line
			(start 0.201 -0.202)
			(end -0.101 0)
			(stroke
				(width 0.15)
				(type solid)
			)
			(layer "F.Fab")
		)
		(fp_line
			(start -0.101 0)
			(end 0.201 0.2)
			(stroke
				(width 0.15)
				(type solid)
			)
			(layer "F.Fab")
		)
		(fp_line
			(start -0.199 0.2)
			(end -0.199 0.1)
			(stroke
				(width 0.15)
				(type solid)
			)
			(layer "F.Fab")
		)
		(fp_line
			(start -0.199 0)
			(end -0.597 0)
			(stroke
				(width 0.15)
				(type solid)
			)
			(layer "F.Fab")
		)
		(fp_line
			(start -0.199 -0.202)
			(end -0.199 0.1)
			(stroke
				(width 0.15)
				(type solid)
			)
			(layer "F.Fab")
		)
		(fp_rect
			(start 0.848 0.4)
			(end -0.85 -0.402)
			(stroke
				(width 0.15)
				(type solid)
			)
			(fill no)
			(layer "F.Fab")
		)
		(fp_text user "Author: Antmicro"
			(at -1.4224 4.799 180)
			(layer "F.Fab")
			(effects
				(font
					(size 0.7 0.7)
					(thickness 0.15)
				)
				(justify left bottom)
			)
		)
		(fp_text user "${REFERENCE}"
			(at -1.4224 5.999 180)
			(layer "F.Fab")
			(effects
				(font
					(size 0.7 0.7)
					(thickness 0.15)
				)
				(justify left bottom)
			)
		)
		(fp_text user "License: Apache-2.0"
			(at -1.4224 3.599 180)
			(layer "F.Fab")
			(effects
				(font
					(size 0.7 0.7)
					(thickness 0.15)
				)
				(justify left bottom)
			)
		)
		(pad "1" smd roundrect
			(at -0.7 0)
			(size 0.8 1)
			(layers "F.Cu" "F.Mask" "F.Paste")
			(roundrect_rratio 0.2)
			(net 414 "Net-(D20-C)")
			(pinfunction "C")
			(pintype "passive")
		)
		(pad "2" smd roundrect
			(at 0.7 0)
			(size 0.8 1)
			(layers "F.Cu" "F.Mask" "F.Paste")
			(roundrect_rratio 0.2)
			(net 255 "/Power/+3V3_OUT")
			(pinfunction "A")
			(pintype "passive")
		)
	)
	(footprint "antmicro-footprints:C_0603_1608Metric"
		(layer "F.Cu")
		(at 72.9 114.3 90)
		(descr "Capacitor SMD 0603")
		(tags "capacitor 0603")
		(property "Reference" "C174"
			(at -2.35 3.74 90)
			(layer "F.SilkS")
			(effects
				(font
					(size 0.7 0.7)
					(thickness 0.15)
				)
				(justify left bottom)
			)
		)
		(property "Value" "C_10u_10V_X7R_0603"
			(at -1.42757 1.770288 90)
			(layer "F.Fab")
			(hide yes)
			(effects
				(font
					(size 0.7 0.7)
					(thickness 0.15)
				)
				(justify left bottom)
			)
		)
		(property "Datasheet" "https://www.murata.com/products/productdetail?partno=GRM188Z71A106KA73%23"
			(at 0 0 90)
			(layer "F.Fab")
			(hide yes)
			(effects
				(font
					(size 1.27 1.27)
					(thickness 0.15)
				)
			)
		)
		(property "Description" "SMD Multilayer Ceramic Capacitor,  10µF, 10V, 0603, ±10%, X7R"
			(at 0 0 90)
			(layer "F.Fab")
			(hide yes)
			(effects
				(font
					(size 1.27 1.27)
					(thickness 0.15)
				)
			)
		)
		(property "MPN" "GRM188Z71A106KA73D"
			(at 0 0 90)
			(unlocked yes)
			(layer "F.Fab")
			(hide yes)
			(effects
				(font
					(size 1 1)
					(thickness 0.15)
				)
			)
		)
		(property "Val" "10u"
			(at 0 0 90)
			(unlocked yes)
			(layer "F.Fab")
			(hide yes)
			(effects
				(font
					(size 1 1)
					(thickness 0.15)
				)
			)
		)
		(property "Voltage" "10V"
			(at 0 0 90)
			(unlocked yes)
			(layer "F.Fab")
			(hide yes)
			(effects
				(font
					(size 1 1)
					(thickness 0.15)
				)
			)
		)
		(property "Dielectric" "X7R"
			(at 0 0 90)
			(unlocked yes)
			(layer "F.Fab")
			(hide yes)
			(effects
				(font
					(size 1 1)
					(thickness 0.15)
				)
			)
		)
		(property "Manufacturer" "Murata"
			(at 0 0 90)
			(unlocked yes)
			(layer "F.Fab")
			(hide yes)
			(effects
				(font
					(size 1 1)
					(thickness 0.15)
				)
			)
		)
		(property "License" "Apache-2.0"
			(at 0 0 90)
			(unlocked yes)
			(layer "F.Fab")
			(hide yes)
			(effects
				(font
					(size 1 1)
					(thickness 0.15)
				)
			)
		)
		(property "Author" "Antmicro"
			(at 0 0 90)
			(unlocked yes)
			(layer "F.Fab")
			(hide yes)
			(effects
				(font
					(size 1 1)
					(thickness 0.15)
				)
			)
		)
		(sheetname "/X710-AT2 power/")
		(sheetfile "x710-at2-power.kicad_sch")
		(attr smd)
		(fp_line
			(start -0.15 -0.4)
			(end 0.15 -0.4)
			(stroke
				(width 0.15)
				(type solid)
			)
			(layer "F.SilkS")
		)
		(fp_line
			(start -0.15 0.4)
			(end 0.15 0.4)
			(stroke
				(width 0.15)
				(type solid)
			)
			(layer "F.SilkS")
		)
		(fp_rect
			(start -1.25 -0.65)
			(end 1.25 0.65)
			(stroke
				(width 0.05)
				(type solid)
			)
			(fill no)
			(layer "F.CrtYd")
		)
		(fp_rect
			(start -0.8 -0.4)
			(end 0.8 0.4)
			(stroke
				(width 0.15)
				(type solid)
			)
			(fill no)
			(layer "F.Fab")
		)
		(pad "1" smd roundrect
			(at -0.7 0 90)
			(size 0.8 1)
			(layers "F.Cu" "F.Mask" "F.Paste")
			(roundrect_rratio 0.2)
			(net 28 "GND")
			(pintype "passive")
		)
		(pad "2" smd roundrect
			(at 0.7 0 90)
			(size 0.8 1)
			(layers "F.Cu" "F.Mask" "F.Paste")
			(roundrect_rratio 0.2)
			(net 14 "P1_AVDDL")
			(pintype "passive")
		)
	)
	(footprint "antmicro-footprints:R_0402_1005Metric"
		(layer "F.Cu")
		(at 86.1 112.45 -90)
		(descr "Resistor SMD 0402")
		(tags "resistor SMD 0402")
		(property "Reference" "R72"
			(at -1.05 0.5 90)
			(layer "F.SilkS")
			(effects
				(font
					(size 0.7 0.7)
					(thickness 0.15)
				)
				(justify right bottom)
			)
		)
		(property "Value" "R_1k_0402"
			(at -1.011843 1.772046 90)
			(layer "F.Fab")
			(hide yes)
			(effects
				(font
					(size 0.7 0.7)
					(thickness 0.15)
				)
				(justify right top)
			)
		)
		(property "Datasheet" "https://www.bourns.com/docs/product-datasheets/cr.pdf"
			(at 0 0 90)
			(layer "F.Fab")
			(hide yes)
			(effects
				(font
					(size 1.27 1.27)
					(thickness 0.15)
				)
			)
		)
		(property "Description" "SMD Chip Resistor, 1 kohm, ± 1%, 63 mW, 0402 [1005 Metric], Thick Film, General Purpose"
			(at 0 0 90)
			(layer "F.Fab")
			(hide yes)
			(effects
				(font
					(size 1.27 1.27)
					(thickness 0.15)
				)
			)
		)
		(property "MPN" "CR0402-FX-1001GLF"
			(at 0 0 270)
			(unlocked yes)
			(layer "F.Fab")
			(hide yes)
			(effects
				(font
					(size 1 1)
					(thickness 0.15)
				)
			)
		)
		(property "Manufacturer" "Bourns"
			(at 0 0 270)
			(unlocked yes)
			(layer "F.Fab")
			(hide yes)
			(effects
				(font
					(size 1 1)
					(thickness 0.15)
				)
			)
		)
		(property "License" "Apache-2.0"
			(at 0 0 270)
			(unlocked yes)
			(layer "F.Fab")
			(hide yes)
			(effects
				(font
					(size 1 1)
					(thickness 0.15)
				)
			)
		)
		(property "Author" "Antmicro"
			(at 0 0 270)
			(unlocked yes)
			(layer "F.Fab")
			(hide yes)
			(effects
				(font
					(size 1 1)
					(thickness 0.15)
				)
			)
		)
		(property "Val" "1k"
			(at 0 0 270)
			(unlocked yes)
			(layer "F.Fab")
			(hide yes)
			(effects
				(font
					(size 1 1)
					(thickness 0.15)
				)
			)
		)
		(property "Tolerance" "1%"
			(at 0 0 270)
			(unlocked yes)
			(layer "F.Fab")
			(hide yes)
			(effects
				(font
					(size 1 1)
					(thickness 0.15)
				)
			)
		)
		(sheetname "/X710-AT2 10GbE/")
		(sheetfile "x710-at2-10gbe.kicad_sch")
		(attr smd exclude_from_pos_files exclude_from_bom dnp)
		(fp_rect
			(start -0.925 -0.47)
			(end 0.925 0.47)
			(stroke
				(width 0.05)
				(type default)
			)
			(fill no)
			(layer "F.CrtYd")
		)
		(fp_rect
			(start -0.5 -0.25)
			(end 0.5 0.25)
			(stroke
				(width 0.15)
				(type solid)
			)
			(fill no)
			(layer "F.Fab")
		)
		(pad "1" smd roundrect
			(at -0.48 0 270)
			(size 0.59 0.64)
			(layers "F.Cu" "F.Mask" "F.Paste")
			(roundrect_rratio 0.25)
			(net 293 "/X710-AT2 10GbE/TPIN_3")
			(pintype "passive")
		)
		(pad "2" smd roundrect
			(at 0.48 0 270)
			(size 0.59 0.64)
			(layers "F.Cu" "F.Mask" "F.Paste")
			(roundrect_rratio 0.25)
			(net 18 "+1V88")
			(pintype "passive")
		)
	)
	(footprint "antmicro-footprints:MP_Pad6mm_Drill3.2mm"
		(layer "F.Cu")
		(at 106.975 121.995)
		(property "Reference" "MP8"
			(at 0 -3.2 0)
			(layer "F.SilkS")
			(hide yes)
			(effects
				(font
					(size 0.7 0.7)
					(thickness 0.15)
				)
				(justify left bottom)
			)
		)
		(property "Value" "MP_Pad6mm_Drill3.2mm"
			(at 0 3.9 0)
			(layer "F.Fab")
			(hide yes)
			(effects
				(font
					(size 0.7 0.7)
					(thickness 0.15)
				)
				(justify left bottom)
			)
		)
		(property "Description" "Mechanical part"
			(at 0 0 0)
			(layer "F.Fab")
			(hide yes)
			(effects
				(font
					(size 1.27 1.27)
					(thickness 0.15)
				)
			)
		)
		(property "Author" "Antmicro"
			(at 0 0 0)
			(unlocked yes)
			(layer "F.Fab")
			(hide yes)
			(effects
				(font
					(size 1 1)
					(thickness 0.15)
				)
			)
		)
		(property "License" "Apache-2.0"
			(at 0 0 0)
			(unlocked yes)
			(layer "F.Fab")
			(hide yes)
			(effects
				(font
					(size 1 1)
					(thickness 0.15)
				)
			)
		)
		(sheetname "/")
		(sheetfile "oculink-to-10gbe-adapter.kicad_sch")
		(attr exclude_from_pos_files exclude_from_bom)
		(fp_circle
			(center 0 0)
			(end 3.25 0)
			(stroke
				(width 0.05)
				(type default)
			)
			(fill no)
			(layer "F.CrtYd")
		)
		(fp_text user "Author: Antmicro"
			(at -0.178 7.225 0)
			(layer "F.Fab")
			(effects
				(font
					(size 0.7 0.7)
					(thickness 0.15)
				)
				(justify left bottom)
			)
		)
		(fp_text user "License: Apache-2.0"
			(at -0.178 8.425 0)
			(layer "F.Fab")
			(effects
				(font
					(size 0.7 0.7)
					(thickness 0.15)
				)
				(justify left bottom)
			)
		)
		(fp_text user "${REFERENCE}"
			(at -0.178 6.025 0)
			(layer "F.Fab")
			(effects
				(font
					(size 0.7 0.7)
					(thickness 0.15)
				)
				(justify left bottom)
			)
		)
		(pad "1" thru_hole circle
			(at 0 0)
			(size 6 6)
			(drill 3.2)
			(layers "*.Cu" "*.Mask")
			(remove_unused_layers no)
			(net 28 "GND")
			(pintype "passive")
		)
	)
	(footprint "antmicro-footprints:C_0603_1608Metric"
		(layer "F.Cu")
		(at 71.1 98.3 90)
		(descr "Capacitor SMD 0603")
		(tags "capacitor 0603")
		(property "Reference" "C139"
			(at 1.04 0.73 90)
			(layer "F.SilkS")
			(effects
				(font
					(size 0.7 0.7)
					(thickness 0.15)
				)
				(justify left bottom)
			)
		)
		(property "Value" "C_10u_10V_X7R_0603"
			(at -1.42757 1.770288 90)
			(layer "F.Fab")
			(hide yes)
			(effects
				(font
					(size 0.7 0.7)
					(thickness 0.15)
				)
				(justify left bottom)
			)
		)
		(property "Datasheet" "https://www.murata.com/products/productdetail?partno=GRM188Z71A106KA73%23"
			(at 0 0 90)
			(layer "F.Fab")
			(hide yes)
			(effects
				(font
					(size 1.27 1.27)
					(thickness 0.15)
				)
			)
		)
		(property "Description" "SMD Multilayer Ceramic Capacitor,  10µF, 10V, 0603, ±10%, X7R"
			(at 0 0 90)
			(layer "F.Fab")
			(hide yes)
			(effects
				(font
					(size 1.27 1.27)
					(thickness 0.15)
				)
			)
		)
		(property "MPN" "GRM188Z71A106KA73D"
			(at 0 0 90)
			(unlocked yes)
			(layer "F.Fab")
			(hide yes)
			(effects
				(font
					(size 1 1)
					(thickness 0.15)
				)
			)
		)
		(property "Val" "10u"
			(at 0 0 90)
			(unlocked yes)
			(layer "F.Fab")
			(hide yes)
			(effects
				(font
					(size 1 1)
					(thickness 0.15)
				)
			)
		)
		(property "Voltage" "10V"
			(at 0 0 90)
			(unlocked yes)
			(layer "F.Fab")
			(hide yes)
			(effects
				(font
					(size 1 1)
					(thickness 0.15)
				)
			)
		)
		(property "Dielectric" "X7R"
			(at 0 0 90)
			(unlocked yes)
			(layer "F.Fab")
			(hide yes)
			(effects
				(font
					(size 1 1)
					(thickness 0.15)
				)
			)
		)
		(property "Manufacturer" "Murata"
			(at 0 0 90)
			(unlocked yes)
			(layer "F.Fab")
			(hide yes)
			(effects
				(font
					(size 1 1)
					(thickness 0.15)
				)
			)
		)
		(property "License" "Apache-2.0"
			(at 0 0 90)
			(unlocked yes)
			(layer "F.Fab")
			(hide yes)
			(effects
				(font
					(size 1 1)
					(thickness 0.15)
				)
			)
		)
		(property "Author" "Antmicro"
			(at 0 0 90)
			(unlocked yes)
			(layer "F.Fab")
			(hide yes)
			(effects
				(font
					(size 1 1)
					(thickness 0.15)
				)
			)
		)
		(sheetname "/X710-AT2 power/")
		(sheetfile "x710-at2-power.kicad_sch")
		(attr smd)
		(fp_line
			(start -0.15 -0.4)
			(end 0.15 -0.4)
			(stroke
				(width 0.15)
				(type solid)
			)
			(layer "F.SilkS")
		)
		(fp_line
			(start -0.15 0.4)
			(end 0.15 0.4)
			(stroke
				(width 0.15)
				(type solid)
			)
			(layer "F.SilkS")
		)
		(fp_rect
			(start -1.25 -0.65)
			(end 1.25 0.65)
			(stroke
				(width 0.05)
				(type solid)
			)
			(fill no)
			(layer "F.CrtYd")
		)
		(fp_rect
			(start -0.8 -0.4)
			(end 0.8 0.4)
			(stroke
				(width 0.15)
				(type solid)
			)
			(fill no)
			(layer "F.Fab")
		)
		(pad "1" smd roundrect
			(at -0.7 0 90)
			(size 0.8 1)
			(layers "F.Cu" "F.Mask" "F.Paste")
			(roundrect_rratio 0.2)
			(net 28 "GND")
			(pintype "passive")
		)
		(pad "2" smd roundrect
			(at 0.7 0 90)
			(size 0.8 1)
			(layers "F.Cu" "F.Mask" "F.Paste")
			(roundrect_rratio 0.2)
			(net 10 "AVDDH")
			(pintype "passive")
		)
	)
	(footprint "antmicro-footprints:R_0402_1005Metric"
		(layer "F.Cu")
		(at 73.85 80.039996)
		(descr "Resistor SMD 0402")
		(tags "resistor SMD 0402")
		(property "Reference" "R3"
			(at -3.86 -8.469996 0)
			(layer "F.SilkS")
			(effects
				(font
					(size 0.7 0.7)
					(thickness 0.15)
				)
				(justify left bottom)
			)
		)
		(property "Value" "R_90k9_0402"
			(at -1.011843 1.772046 0)
			(layer "F.Fab")
			(hide yes)
			(effects
				(font
					(size 0.7 0.7)
					(thickness 0.15)
				)
				(justify left bottom)
			)
		)
		(property "Datasheet" "https://www.bourns.com/docs/product-datasheets/cr.pdf"
			(at 0 0 0)
			(layer "F.Fab")
			(hide yes)
			(effects
				(font
					(size 1.27 1.27)
					(thickness 0.15)
				)
			)
		)
		(property "Description" "SMD Chip Resistor"
			(at 0 0 0)
			(layer "F.Fab")
			(hide yes)
			(effects
				(font
					(size 1.27 1.27)
					(thickness 0.15)
				)
			)
		)
		(property "MPN" "CR0402-FX-9092GLF"
			(at 0 0 0)
			(unlocked yes)
			(layer "F.Fab")
			(hide yes)
			(effects
				(font
					(size 1 1)
					(thickness 0.15)
				)
			)
		)
		(property "Manufacturer" "Bourns"
			(at 0 0 0)
			(unlocked yes)
			(layer "F.Fab")
			(hide yes)
			(effects
				(font
					(size 1 1)
					(thickness 0.15)
				)
			)
		)
		(property "License" "Apache-2.0"
			(at 0 0 0)
			(unlocked yes)
			(layer "F.Fab")
			(hide yes)
			(effects
				(font
					(size 1 1)
					(thickness 0.15)
				)
			)
		)
		(property "Author" "Antmicro"
			(at 0 0 0)
			(unlocked yes)
			(layer "F.Fab")
			(hide yes)
			(effects
				(font
					(size 1 1)
					(thickness 0.15)
				)
			)
		)
		(property "Val" "90k9"
			(at 0 0 0)
			(unlocked yes)
			(layer "F.Fab")
			(hide yes)
			(effects
				(font
					(size 1 1)
					(thickness 0.15)
				)
			)
		)
		(property "Tolerance" "1%"
			(at 0 0 0)
			(unlocked yes)
			(layer "F.Fab")
			(hide yes)
			(effects
				(font
					(size 1 1)
					(thickness 0.15)
				)
			)
		)
		(sheetname "/Power/")
		(sheetfile "power.kicad_sch")
		(attr smd)
		(fp_rect
			(start -0.925 -0.47)
			(end 0.925 0.47)
			(stroke
				(width 0.05)
				(type default)
			)
			(fill no)
			(layer "F.CrtYd")
		)
		(fp_rect
			(start -0.5 -0.25)
			(end 0.5 0.25)
			(stroke
				(width 0.15)
				(type solid)
			)
			(fill no)
			(layer "F.Fab")
		)
		(pad "1" smd roundrect
			(at -0.48 0)
			(size 0.59 0.64)
			(layers "F.Cu" "F.Mask" "F.Paste")
			(roundrect_rratio 0.25)
			(net 317 "/Power/3V3_FB")
			(pintype "passive")
		)
		(pad "2" smd roundrect
			(at 0.48 0)
			(size 0.59 0.64)
			(layers "F.Cu" "F.Mask" "F.Paste")
			(roundrect_rratio 0.25)
			(net 255 "/Power/+3V3_OUT")
			(pintype "passive")
		)
	)
)
